("..\\packaged\\pstdmlmodels.dat" 
 (PackagedDevice 
  (DEFAULT_CAPACITOR_100000PF_2_1 
   (ESpice ".subckt DEFAULT_CAPACITOR_100000PF_2_1 1 2
C1 1 2 1e-007
.ends DEFAULT_CAPACITOR_100000PF_2_1
" ) 
   (PinConnections 
    (1 2 ) 
    (2 1 ) ) ) ) 
 (LibraryVersion 136.2 ) ) 